# T6G (Grand Teton) — schematic netlist excerpt (pin names and nets, part order shuffled) for the footprints in the layout excerpt that follows; sources: Cadence DE-HDL packaged netlist, KiCad conversion of 04192023_DAF0TMB3IC0_F0TG_MB_C_brd_V02_OCP.brd

R6157  Q_RES  0 5% CHIP  pkg 0201LF  page 113 : A = P2E_MB_BMC_RX_DN<0> ; B = P2E_MB_BMC_RX_R1_DN<0>
R216  Q_RES  33 5% CHIP  pkg 0402LF  page 81 : A = RST_CPU0_SYS_N ; B = FM_CPU0_SYS_RESET_N
C6631  Q_CAP_DIFFBUS  DIFF BUS_0.22UF 6.3V 20% X6S  pkg C0201  page 319 : \1\ = P5E_CPU1_P0_TX_BUF_C_DP<1> ; \2\ = P5E_CPU1_P0_TX_BUF_DP<1>

(kicad_pcb
	(version 20260206)
	(generator "pcbnew")
	(generator_version "10.0")
	(general
		(thickness 1.6)
		(legacy_teardrops no)
	)
	(paper "A4")
	(title_block
		(title "04192023_DAF0TMB3IC0_F0TG_MB_C_brd_V02_OCP.brd")
		(comment 1 "Grand Teton / footprints 3007-3009 of 8354")
	)
	(layers
		(0 "F.Cu" signal "TOP")
		(4 "In1.Cu" signal "GND")
		(6 "In2.Cu" signal "IN1")
		(8 "In3.Cu" signal "GND1")
		(10 "In4.Cu" signal "IN2")
		(12 "In5.Cu" signal "GND2")
		(14 "In6.Cu" signal "IN3")
		(16 "In7.Cu" signal "GND3")
		(18 "In8.Cu" signal "VCC")
		(20 "In9.Cu" signal "VCC1")
		(22 "In10.Cu" signal "GND4")
		(24 "In11.Cu" signal "IN4")
		(26 "In12.Cu" signal "GND5")
		(28 "In13.Cu" signal "IN5")
		(30 "In14.Cu" signal "GND6")
		(32 "In15.Cu" signal "IN6")
		(34 "In16.Cu" signal "GND7")
		(2 "B.Cu" signal "BOTTOM")
		(9 "F.Adhes" user "F.Adhesive")
		(11 "B.Adhes" user "B.Adhesive")
		(13 "F.Paste" user "Package Geometry/Pastemask Top")
		(15 "B.Paste" user "Package Geometry/Pastemask Bottom")
		(5 "F.SilkS" user "Ref Des/Silkscreen Top")
		(7 "B.SilkS" user "Ref Des/Silkscreen Bottom")
		(1 "F.Mask" user "Board Geometry/Soldermask Top")
		(3 "B.Mask" user "Board Geometry/Soldermask Bottom")
		(17 "Dwgs.User" user "User.Drawings")
		(19 "Cmts.User" user "User.Comments")
		(21 "Eco1.User" user "User.Eco1")
		(23 "Eco2.User" user "User.Eco2")
		(25 "Edge.Cuts" user "Board Geometry/Outline")
		(27 "Margin" user)
		(31 "F.CrtYd" user "Package Geometry/Place Bound Top")
		(29 "B.CrtYd" user "Package Geometry/Place Bound Bottom")
		(35 "F.Fab" user "Ref Des/Assembly Top")
		(33 "B.Fab" user "Ref Des/Assembly Bottom")
	)
	(footprint ""
		(layer "F.Cu")
		(at 178.943 -133.568948 -90)
		(property "Reference" "R216"
			(at 0 0 270)
			(layer "F.SilkS")
			(hide yes)
			(effects
				(font
					(size 1.27 1.27)
				)
			)
		)
		(property "Value" ""
			(at 0 0 270)
			(layer "F.Fab")
			(effects
				(font
					(size 1.27 1.27)
				)
			)
		)
		(duplicate_pad_numbers_are_jumpers no)
		(fp_line
			(start -0.7874 0.4064)
			(end -0.7874 -0.4064)
			(stroke
				(width 0.1524)
				(type default)
			)
			(layer "F.SilkS")
		)
		(fp_line
			(start 0.7874 0.4064)
			(end -0.7874 0.4064)
			(stroke
				(width 0.1524)
				(type default)
			)
			(layer "F.SilkS")
		)
		(fp_line
			(start -0.7874 -0.4064)
			(end 0.7874 -0.4064)
			(stroke
				(width 0.1524)
				(type default)
			)
			(layer "F.SilkS")
		)
		(fp_line
			(start 0.7874 -0.4064)
			(end 0.7874 0.4064)
			(stroke
				(width 0.1524)
				(type default)
			)
			(layer "F.SilkS")
		)
		(fp_line
			(start -0.67945 0.3048)
			(end -0.67945 -0.305054)
			(stroke
				(width 0.1)
				(type default)
			)
			(layer "F.Fab")
		)
		(fp_line
			(start -0.12065 0.3048)
			(end -0.67945 0.3048)
			(stroke
				(width 0.1)
				(type default)
			)
			(layer "F.Fab")
		)
		(fp_line
			(start 0.120396 0.3048)
			(end 0.120396 0.2794)
			(stroke
				(width 0.1)
				(type default)
			)
			(layer "F.Fab")
		)
		(fp_line
			(start 0.67945 0.3048)
			(end 0.120396 0.3048)
			(stroke
				(width 0.1)
				(type default)
			)
			(layer "F.Fab")
		)
		(fp_line
			(start -0.12065 0.2794)
			(end -0.12065 0.3048)
			(stroke
				(width 0.1)
				(type default)
			)
			(layer "F.Fab")
		)
		(fp_line
			(start 0.120396 0.2794)
			(end -0.12065 0.2794)
			(stroke
				(width 0.1)
				(type default)
			)
			(layer "F.Fab")
		)
		(fp_line
			(start -0.12065 -0.2794)
			(end 0.12065 -0.2794)
			(stroke
				(width 0.1)
				(type default)
			)
			(layer "F.Fab")
		)
		(fp_line
			(start 0.12065 -0.2794)
			(end 0.12065 -0.3048)
			(stroke
				(width 0.1)
				(type default)
			)
			(layer "F.Fab")
		)
		(fp_line
			(start 0.12065 -0.3048)
			(end 0.67945 -0.3048)
			(stroke
				(width 0.1)
				(type default)
			)
			(layer "F.Fab")
		)
		(fp_line
			(start 0.67945 -0.3048)
			(end 0.67945 0.3048)
			(stroke
				(width 0.1)
				(type default)
			)
			(layer "F.Fab")
		)
		(fp_line
			(start -0.67945 -0.305054)
			(end -0.12065 -0.305054)
			(stroke
				(width 0.1)
				(type default)
			)
			(layer "F.Fab")
		)
		(fp_line
			(start -0.12065 -0.305054)
			(end -0.12065 -0.2794)
			(stroke
				(width 0.1)
				(type default)
			)
			(layer "F.Fab")
		)
		(pad "1" smd circle
			(at -0.40005 0 270)
			(size 0 0)
			(layers "F.Cu" "F.Mask" "F.Paste")
			(net "RST_CPU0_SYS_N")
		)
		(pad "2" smd circle
			(at 0.40005 0 270)
			(size 0 0)
			(layers "F.Cu" "F.Mask" "F.Paste")
			(net "FM_CPU0_SYS_RESET_N")
		)
	)
	(footprint ""
		(layer "F.Cu")
		(at 28.021026 -427.612302)
		(property "Reference" "R6157"
			(at 0 0 0)
			(layer "F.SilkS")
			(hide yes)
			(effects
				(font
					(size 1.27 1.27)
				)
			)
		)
		(property "Value" ""
			(at 0 0 0)
			(layer "F.Fab")
			(effects
				(font
					(size 1.27 1.27)
				)
			)
		)
		(duplicate_pad_numbers_are_jumpers no)
		(fp_line
			(start -0.32512 -0.175006)
			(end 0.32512 -0.175006)
			(stroke
				(width 0.1)
				(type default)
			)
			(layer "F.Fab")
		)
		(fp_line
			(start -0.32512 0.175006)
			(end -0.32512 -0.175006)
			(stroke
				(width 0.1)
				(type default)
			)
			(layer "F.Fab")
		)
		(fp_line
			(start 0.32512 -0.175006)
			(end 0.32512 0.175006)
			(stroke
				(width 0.1)
				(type default)
			)
			(layer "F.Fab")
		)
		(fp_line
			(start 0.32512 0.175006)
			(end -0.32512 0.175006)
			(stroke
				(width 0.1)
				(type default)
			)
			(layer "F.Fab")
		)
		(pad "1" smd rect
			(at -0.2667 0)
			(size 0.3048 0.381)
			(layers "F.Cu" "F.Mask" "F.Paste")
			(net "P2E_MB_BMC_RX_DN<0>")
		)
		(pad "2" smd rect
			(at 0.2667 0 180)
			(size 0.3048 0.381)
			(layers "F.Cu" "F.Mask" "F.Paste")
			(net "P2E_MB_BMC_RX_R1_DN<0>")
		)
	)
	(footprint ""
		(layer "F.Cu")
		(at 51.746404 -408.517344 -90)
		(property "Reference" "C6631"
			(at 0 0 270)
			(layer "F.SilkS")
			(hide yes)
			(effects
				(font
					(size 1.27 1.27)
				)
			)
		)
		(property "Value" ""
			(at 0 0 270)
			(layer "F.Fab")
			(effects
				(font
					(size 1.27 1.27)
				)
			)
		)
		(duplicate_pad_numbers_are_jumpers no)
		(fp_line
			(start -0.299974 0.150114)
			(end -0.299974 -0.150114)
			(stroke
				(width 0.1)
				(type default)
			)
			(layer "F.Fab")
		)
		(fp_line
			(start 0.299974 0.150114)
			(end -0.299974 0.150114)
			(stroke
				(width 0.1)
				(type default)
			)
			(layer "F.Fab")
		)
		(fp_line
			(start -0.299974 -0.150114)
			(end 0.299974 -0.150114)
			(stroke
				(width 0.1)
				(type default)
			)
			(layer "F.Fab")
		)
		(fp_line
			(start 0.299974 -0.150114)
			(end 0.299974 0.150114)
			(stroke
				(width 0.1)
				(type default)
			)
			(layer "F.Fab")
		)
		(pad "1" smd rect
			(at -0.2667 0 270)
			(size 0.3048 0.381)
			(layers "F.Cu" "F.Mask" "F.Paste")
			(net "P5E_CPU1_P0_TX_BUF_C_DP<1>")
		)
		(pad "2" smd rect
			(at 0.2667 0 270)
			(size 0.3048 0.381)
			(layers "F.Cu" "F.Mask" "F.Paste")
			(net "P5E_CPU1_P0_TX_BUF_DP<1>")
		)
	)
)
